(kicad_pcb
	(version 20260206)
	(generator "pcbnew")
	(generator_version "10.0")
	(general
		(thickness 1.6)
		(legacy_teardrops no)
	)
	(paper "A4")
	(title_block
		(title "01162023_DA0F0TEBIF0_F0T_Expander_BD_F_brd_V02_OCP.brd")
		(comment 1 "Grand Teton / footprints 7011-7016 of 9728")
	)
	(layers
		(0 "F.Cu" signal "TOP")
		(4 "In1.Cu" signal "GND")
		(6 "In2.Cu" signal "VCC")
		(8 "In3.Cu" signal "VCC1")
		(10 "In4.Cu" signal "GND1")
		(12 "In5.Cu" signal "IN1")
		(14 "In6.Cu" signal "GND2")
		(16 "In7.Cu" signal "IN2")
		(18 "In8.Cu" signal "GND3")
		(20 "In9.Cu" signal "IN3")
		(22 "In10.Cu" signal "GND4")
		(24 "In11.Cu" signal "IN4")
		(26 "In12.Cu" signal "GND5")
		(28 "In13.Cu" signal "IN5")
		(30 "In14.Cu" signal "GND6")
		(32 "In15.Cu" signal "IN6")
		(34 "In16.Cu" signal "GND7")
		(2 "B.Cu" signal "BOTTOM")
		(9 "F.Adhes" user "F.Adhesive")
		(11 "B.Adhes" user "B.Adhesive")
		(13 "F.Paste" user "Package Geometry/Pastemask Top")
		(15 "B.Paste" user "Package Geometry/Pastemask Bottom")
		(5 "F.SilkS" user "Ref Des/Silkscreen Top")
		(7 "B.SilkS" user "Ref Des/Silkscreen Bottom")
		(1 "F.Mask" user "Board Geometry/Soldermask Top")
		(3 "B.Mask" user "Board Geometry/Soldermask Bottom")
		(17 "Dwgs.User" user "User.Drawings")
		(19 "Cmts.User" user "User.Comments")
		(21 "Eco1.User" user "User.Eco1")
		(23 "Eco2.User" user "User.Eco2")
		(25 "Edge.Cuts" user "Board Geometry/Outline")
		(27 "Margin" user)
		(31 "F.CrtYd" user "Package Geometry/Place Bound Top")
		(29 "B.CrtYd" user "Package Geometry/Place Bound Bottom")
		(35 "F.Fab" user "Ref Des/Assembly Top")
		(33 "B.Fab" user "Ref Des/Assembly Bottom")
	)
	(footprint ""
		(layer "F.Cu")
		(at 338.074 -180.975 180)
		(property "Reference" "R4751"
			(at 0 0 180)
			(layer "F.SilkS")
			(hide yes)
			(effects
				(font
					(size 1.27 1.27)
				)
			)
		)
		(property "Value" ""
			(at 0 0 180)
			(layer "F.Fab")
			(effects
				(font
					(size 1.27 1.27)
				)
			)
		)
		(duplicate_pad_numbers_are_jumpers no)
		(fp_line
			(start 0.7874 0.4064)
			(end -0.7874 0.4064)
			(stroke
				(width 0.1524)
				(type default)
			)
			(layer "F.SilkS")
		)
		(fp_line
			(start 0.7874 -0.4064)
			(end 0.7874 0.4064)
			(stroke
				(width 0.1524)
				(type default)
			)
			(layer "F.SilkS")
		)
		(fp_line
			(start -0.7874 0.4064)
			(end -0.7874 -0.4064)
			(stroke
				(width 0.1524)
				(type default)
			)
			(layer "F.SilkS")
		)
		(fp_line
			(start -0.7874 -0.4064)
			(end 0.7874 -0.4064)
			(stroke
				(width 0.1524)
				(type default)
			)
			(layer "F.SilkS")
		)
		(fp_line
			(start 0.67945 0.3048)
			(end 0.120396 0.3048)
			(stroke
				(width 0.1)
				(type default)
			)
			(layer "F.Fab")
		)
		(fp_line
			(start 0.67945 -0.3048)
			(end 0.67945 0.3048)
			(stroke
				(width 0.1)
				(type default)
			)
			(layer "F.Fab")
		)
		(fp_line
			(start 0.12065 -0.2794)
			(end 0.12065 -0.3048)
			(stroke
				(width 0.1)
				(type default)
			)
			(layer "F.Fab")
		)
		(fp_line
			(start 0.12065 -0.3048)
			(end 0.67945 -0.3048)
			(stroke
				(width 0.1)
				(type default)
			)
			(layer "F.Fab")
		)
		(fp_line
			(start 0.120396 0.3048)
			(end 0.120396 0.2794)
			(stroke
				(width 0.1)
				(type default)
			)
			(layer "F.Fab")
		)
		(fp_line
			(start 0.120396 0.2794)
			(end -0.12065 0.2794)
			(stroke
				(width 0.1)
				(type default)
			)
			(layer "F.Fab")
		)
		(fp_line
			(start -0.12065 0.3048)
			(end -0.67945 0.3048)
			(stroke
				(width 0.1)
				(type default)
			)
			(layer "F.Fab")
		)
		(fp_line
			(start -0.12065 0.2794)
			(end -0.12065 0.3048)
			(stroke
				(width 0.1)
				(type default)
			)
			(layer "F.Fab")
		)
		(fp_line
			(start -0.12065 -0.2794)
			(end 0.12065 -0.2794)
			(stroke
				(width 0.1)
				(type default)
			)
			(layer "F.Fab")
		)
		(fp_line
			(start -0.12065 -0.305054)
			(end -0.12065 -0.2794)
			(stroke
				(width 0.1)
				(type default)
			)
			(layer "F.Fab")
		)
		(fp_line
			(start -0.67945 0.3048)
			(end -0.67945 -0.305054)
			(stroke
				(width 0.1)
				(type default)
			)
			(layer "F.Fab")
		)
		(fp_line
			(start -0.67945 -0.305054)
			(end -0.12065 -0.305054)
			(stroke
				(width 0.1)
				(type default)
			)
			(layer "F.Fab")
		)
		(pad "1" smd circle
			(at -0.40005 0 180)
			(size 0 0)
			(layers "F.Cu" "F.Mask" "F.Paste")
			(net "RST_PEX_SSD8_PERST_N")
		)
		(pad "2" smd circle
			(at 0.40005 0 180)
			(size 0 0)
			(layers "F.Cu" "F.Mask" "F.Paste")
			(net "RST_PEX_SSD8_PERST_R_N")
		)
	)
	(footprint ""
		(layer "F.Cu")
		(at 26.267918 -53.051456)
		(property "Reference" "R4458"
			(at 0 0 0)
			(layer "F.SilkS")
			(hide yes)
			(effects
				(font
					(size 1.27 1.27)
				)
			)
		)
		(property "Value" ""
			(at 0 0 0)
			(layer "F.Fab")
			(effects
				(font
					(size 1.27 1.27)
				)
			)
		)
		(duplicate_pad_numbers_are_jumpers no)
		(fp_line
			(start -0.7874 -0.4064)
			(end 0.7874 -0.4064)
			(stroke
				(width 0.1524)
				(type default)
			)
			(layer "F.SilkS")
		)
		(fp_line
			(start -0.7874 0.4064)
			(end -0.7874 -0.4064)
			(stroke
				(width 0.1524)
				(type default)
			)
			(layer "F.SilkS")
		)
		(fp_line
			(start 0.7874 -0.4064)
			(end 0.7874 0.4064)
			(stroke
				(width 0.1524)
				(type default)
			)
			(layer "F.SilkS")
		)
		(fp_line
			(start 0.7874 0.4064)
			(end -0.7874 0.4064)
			(stroke
				(width 0.1524)
				(type default)
			)
			(layer "F.SilkS")
		)
		(fp_line
			(start -0.67945 -0.305054)
			(end -0.12065 -0.305054)
			(stroke
				(width 0.1)
				(type default)
			)
			(layer "F.Fab")
		)
		(fp_line
			(start -0.67945 0.3048)
			(end -0.67945 -0.305054)
			(stroke
				(width 0.1)
				(type default)
			)
			(layer "F.Fab")
		)
		(fp_line
			(start -0.12065 -0.305054)
			(end -0.12065 -0.2794)
			(stroke
				(width 0.1)
				(type default)
			)
			(layer "F.Fab")
		)
		(fp_line
			(start -0.12065 -0.2794)
			(end 0.12065 -0.2794)
			(stroke
				(width 0.1)
				(type default)
			)
			(layer "F.Fab")
		)
		(fp_line
			(start -0.12065 0.2794)
			(end -0.12065 0.3048)
			(stroke
				(width 0.1)
				(type default)
			)
			(layer "F.Fab")
		)
		(fp_line
			(start -0.12065 0.3048)
			(end -0.67945 0.3048)
			(stroke
				(width 0.1)
				(type default)
			)
			(layer "F.Fab")
		)
		(fp_line
			(start 0.120396 0.2794)
			(end -0.12065 0.2794)
			(stroke
				(width 0.1)
				(type default)
			)
			(layer "F.Fab")
		)
		(fp_line
			(start 0.120396 0.3048)
			(end 0.120396 0.2794)
			(stroke
				(width 0.1)
				(type default)
			)
			(layer "F.Fab")
		)
		(fp_line
			(start 0.12065 -0.3048)
			(end 0.67945 -0.3048)
			(stroke
				(width 0.1)
				(type default)
			)
			(layer "F.Fab")
		)
		(fp_line
			(start 0.12065 -0.2794)
			(end 0.12065 -0.3048)
			(stroke
				(width 0.1)
				(type default)
			)
			(layer "F.Fab")
		)
		(fp_line
			(start 0.67945 -0.3048)
			(end 0.67945 0.3048)
			(stroke
				(width 0.1)
				(type default)
			)
			(layer "F.Fab")
		)
		(fp_line
			(start 0.67945 0.3048)
			(end 0.120396 0.3048)
			(stroke
				(width 0.1)
				(type default)
			)
			(layer "F.Fab")
		)
		(pad "1" smd circle
			(at -0.40005 0)
			(size 0 0)
			(layers "F.Cu" "F.Mask" "F.Paste")
			(net "PWRGD_P12V_SSD0")
		)
		(pad "2" smd circle
			(at 0.40005 0)
			(size 0 0)
			(layers "F.Cu" "F.Mask" "F.Paste")
			(net "PWRGD_P12V_SSD0_R")
		)
	)
	(footprint ""
		(layer "F.Cu")
		(at 98.873818 -103.668068)
		(property "Reference" "PC321"
			(at 0 0 0)
			(layer "F.SilkS")
			(hide yes)
			(effects
				(font
					(size 1.27 1.27)
				)
			)
		)
		(property "Value" ""
			(at 0 0 0)
			(layer "F.Fab")
			(effects
				(font
					(size 1.27 1.27)
				)
			)
		)
		(duplicate_pad_numbers_are_jumpers no)
		(fp_line
			(start -1.524 -0.762)
			(end 1.524 -0.762)
			(stroke
				(width 0.1524)
				(type default)
			)
			(layer "F.SilkS")
		)
		(fp_line
			(start -1.524 0.762)
			(end -1.524 -0.762)
			(stroke
				(width 0.1524)
				(type default)
			)
			(layer "F.SilkS")
		)
		(fp_line
			(start 1.524 -0.762)
			(end 1.524 0.762)
			(stroke
				(width 0.1524)
				(type default)
			)
			(layer "F.SilkS")
		)
		(fp_line
			(start 1.524 0.762)
			(end -1.524 0.762)
			(stroke
				(width 0.1524)
				(type default)
			)
			(layer "F.SilkS")
		)
		(fp_line
			(start -1.1049 -0.724916)
			(end -1.1049 0.724916)
			(stroke
				(width 0.1)
				(type default)
			)
			(layer "F.Fab")
		)
		(fp_line
			(start -1.1049 0.724916)
			(end 1.1049 0.724916)
			(stroke
				(width 0.1)
				(type default)
			)
			(layer "F.Fab")
		)
		(fp_line
			(start 1.1049 -0.724916)
			(end -1.1049 -0.724916)
			(stroke
				(width 0.1)
				(type default)
			)
			(layer "F.Fab")
		)
		(fp_line
			(start 1.1049 0.724916)
			(end 1.1049 -0.724916)
			(stroke
				(width 0.1)
				(type default)
			)
			(layer "F.Fab")
		)
		(pad "1" smd rect
			(at -0.889 0 180)
			(size 1.016 1.27)
			(layers "F.Cu" "F.Mask" "F.Paste")
			(net "P12V_NIC1_R")
		)
		(pad "2" smd rect
			(at 0.889 0 180)
			(size 1.016 1.27)
			(layers "F.Cu" "F.Mask" "F.Paste")
			(net "GND")
		)
	)
	(footprint ""
		(layer "F.Cu")
		(at 21.530564 -66.32194 -90)
		(property "Reference" "PC646"
			(at 0 0 270)
			(layer "F.SilkS")
			(hide yes)
			(effects
				(font
					(size 1.27 1.27)
				)
			)
		)
		(property "Value" ""
			(at 0 0 270)
			(layer "F.Fab")
			(effects
				(font
					(size 1.27 1.27)
				)
			)
		)
		(duplicate_pad_numbers_are_jumpers no)
		(fp_line
			(start -0.7874 0.4064)
			(end -0.7874 -0.4064)
			(stroke
				(width 0.1524)
				(type default)
			)
			(layer "F.SilkS")
		)
		(fp_line
			(start 0.7874 0.4064)
			(end -0.7874 0.4064)
			(stroke
				(width 0.1524)
				(type default)
			)
			(layer "F.SilkS")
		)
		(fp_line
			(start -0.7874 -0.4064)
			(end 0.7874 -0.4064)
			(stroke
				(width 0.1524)
				(type default)
			)
			(layer "F.SilkS")
		)
		(fp_line
			(start 0.7874 -0.4064)
			(end 0.7874 0.4064)
			(stroke
				(width 0.1524)
				(type default)
			)
			(layer "F.SilkS")
		)
		(fp_line
			(start -0.67945 0.3048)
			(end -0.67945 -0.305054)
			(stroke
				(width 0.1)
				(type default)
			)
			(layer "F.Fab")
		)
		(fp_line
			(start -0.12065 0.3048)
			(end -0.67945 0.3048)
			(stroke
				(width 0.1)
				(type default)
			)
			(layer "F.Fab")
		)
		(fp_line
			(start 0.120396 0.3048)
			(end 0.120396 0.2794)
			(stroke
				(width 0.1)
				(type default)
			)
			(layer "F.Fab")
		)
		(fp_line
			(start 0.67945 0.3048)
			(end 0.120396 0.3048)
			(stroke
				(width 0.1)
				(type default)
			)
			(layer "F.Fab")
		)
		(fp_line
			(start -0.12065 0.2794)
			(end -0.12065 0.3048)
			(stroke
				(width 0.1)
				(type default)
			)
			(layer "F.Fab")
		)
		(fp_line
			(start 0.120396 0.2794)
			(end -0.12065 0.2794)
			(stroke
				(width 0.1)
				(type default)
			)
			(layer "F.Fab")
		)
		(fp_line
			(start -0.12065 -0.2794)
			(end 0.12065 -0.2794)
			(stroke
				(width 0.1)
				(type default)
			)
			(layer "F.Fab")
		)
		(fp_line
			(start 0.12065 -0.2794)
			(end 0.12065 -0.3048)
			(stroke
				(width 0.1)
				(type default)
			)
			(layer "F.Fab")
		)
		(fp_line
			(start 0.12065 -0.3048)
			(end 0.67945 -0.3048)
			(stroke
				(width 0.1)
				(type default)
			)
			(layer "F.Fab")
		)
		(fp_line
			(start 0.67945 -0.3048)
			(end 0.67945 0.3048)
			(stroke
				(width 0.1)
				(type default)
			)
			(layer "F.Fab")
		)
		(fp_line
			(start -0.67945 -0.305054)
			(end -0.12065 -0.305054)
			(stroke
				(width 0.1)
				(type default)
			)
			(layer "F.Fab")
		)
		(fp_line
			(start -0.12065 -0.305054)
			(end -0.12065 -0.2794)
			(stroke
				(width 0.1)
				(type default)
			)
			(layer "F.Fab")
		)
		(pad "1" smd circle
			(at -0.40005 0 270)
			(size 0 0)
			(layers "F.Cu" "F.Mask" "F.Paste")
			(net "P12V_SSD0_CO_DV_DT")
		)
		(pad "2" smd circle
			(at 0.40005 0 270)
			(size 0 0)
			(layers "F.Cu" "F.Mask" "F.Paste")
			(net "GND")
		)
	)
	(footprint ""
		(layer "F.Cu")
		(at 451.211188 -415.621216 90)
		(property "Reference" "R5607"
			(at 0 0 90)
			(layer "F.SilkS")
			(hide yes)
			(effects
				(font
					(size 1.27 1.27)
				)
			)
		)
		(property "Value" ""
			(at 0 0 90)
			(layer "F.Fab")
			(effects
				(font
					(size 1.27 1.27)
				)
			)
		)
		(duplicate_pad_numbers_are_jumpers no)
		(fp_line
			(start 0.7874 -0.4064)
			(end 0.7874 0.4064)
			(stroke
				(width 0.1524)
				(type default)
			)
			(layer "F.SilkS")
		)
		(fp_line
			(start -0.7874 -0.4064)
			(end 0.7874 -0.4064)
			(stroke
				(width 0.1524)
				(type default)
			)
			(layer "F.SilkS")
		)
		(fp_line
			(start 0.7874 0.4064)
			(end -0.7874 0.4064)
			(stroke
				(width 0.1524)
				(type default)
			)
			(layer "F.SilkS")
		)
		(fp_line
			(start -0.7874 0.4064)
			(end -0.7874 -0.4064)
			(stroke
				(width 0.1524)
				(type default)
			)
			(layer "F.SilkS")
		)
		(fp_line
			(start -0.12065 -0.305054)
			(end -0.12065 -0.2794)
			(stroke
				(width 0.1)
				(type default)
			)
			(layer "F.Fab")
		)
		(fp_line
			(start -0.67945 -0.305054)
			(end -0.12065 -0.305054)
			(stroke
				(width 0.1)
				(type default)
			)
			(layer "F.Fab")
		)
		(fp_line
			(start 0.67945 -0.3048)
			(end 0.67945 0.3048)
			(stroke
				(width 0.1)
				(type default)
			)
			(layer "F.Fab")
		)
		(fp_line
			(start 0.12065 -0.3048)
			(end 0.67945 -0.3048)
			(stroke
				(width 0.1)
				(type default)
			)
			(layer "F.Fab")
		)
		(fp_line
			(start 0.12065 -0.2794)
			(end 0.12065 -0.3048)
			(stroke
				(width 0.1)
				(type default)
			)
			(layer "F.Fab")
		)
		(fp_line
			(start -0.12065 -0.2794)
			(end 0.12065 -0.2794)
			(stroke
				(width 0.1)
				(type default)
			)
			(layer "F.Fab")
		)
		(fp_line
			(start 0.120396 0.2794)
			(end -0.12065 0.2794)
			(stroke
				(width 0.1)
				(type default)
			)
			(layer "F.Fab")
		)
		(fp_line
			(start -0.12065 0.2794)
			(end -0.12065 0.3048)
			(stroke
				(width 0.1)
				(type default)
			)
			(layer "F.Fab")
		)
		(fp_line
			(start 0.67945 0.3048)
			(end 0.120396 0.3048)
			(stroke
				(width 0.1)
				(type default)
			)
			(layer "F.Fab")
		)
		(fp_line
			(start 0.120396 0.3048)
			(end 0.120396 0.2794)
			(stroke
				(width 0.1)
				(type default)
			)
			(layer "F.Fab")
		)
		(fp_line
			(start -0.12065 0.3048)
			(end -0.67945 0.3048)
			(stroke
				(width 0.1)
				(type default)
			)
			(layer "F.Fab")
		)
		(fp_line
			(start -0.67945 0.3048)
			(end -0.67945 -0.305054)
			(stroke
				(width 0.1)
				(type default)
			)
			(layer "F.Fab")
		)
		(pad "1" smd circle
			(at -0.40005 0 90)
			(size 0 0)
			(layers "F.Cu" "F.Mask" "F.Paste")
			(net "LM75_1_A2")
		)
		(pad "2" smd circle
			(at 0.40005 0 90)
			(size 0 0)
			(layers "F.Cu" "F.Mask" "F.Paste")
			(net "GND")
		)
	)
	(footprint ""
		(layer "F.Cu")
		(at 293.394892 -59.577986 90)
		(property "Reference" "PC578"
			(at 0 0 90)
			(layer "F.SilkS")
			(hide yes)
			(effects
				(font
					(size 1.27 1.27)
				)
			)
		)
		(property "Value" ""
			(at 0 0 90)
			(layer "F.Fab")
			(effects
				(font
					(size 1.27 1.27)
				)
			)
		)
		(duplicate_pad_numbers_are_jumpers no)
		(fp_line
			(start 0.7874 -0.4064)
			(end 0.7874 0.4064)
			(stroke
				(width 0.1524)
				(type default)
			)
			(layer "F.SilkS")
		)
		(fp_line
			(start -0.7874 -0.4064)
			(end 0.7874 -0.4064)
			(stroke
				(width 0.1524)
				(type default)
			)
			(layer "F.SilkS")
		)
		(fp_line
			(start 0.7874 0.4064)
			(end -0.7874 0.4064)
			(stroke
				(width 0.1524)
				(type default)
			)
			(layer "F.SilkS")
		)
		(fp_line
			(start -0.7874 0.4064)
			(end -0.7874 -0.4064)
			(stroke
				(width 0.1524)
				(type default)
			)
			(layer "F.SilkS")
		)
		(fp_line
			(start -0.12065 -0.305054)
			(end -0.12065 -0.2794)
			(stroke
				(width 0.1)
				(type default)
			)
			(layer "F.Fab")
		)
		(fp_line
			(start -0.67945 -0.305054)
			(end -0.12065 -0.305054)
			(stroke
				(width 0.1)
				(type default)
			)
			(layer "F.Fab")
		)
		(fp_line
			(start 0.67945 -0.3048)
			(end 0.67945 0.3048)
			(stroke
				(width 0.1)
				(type default)
			)
			(layer "F.Fab")
		)
		(fp_line
			(start 0.12065 -0.3048)
			(end 0.67945 -0.3048)
			(stroke
				(width 0.1)
				(type default)
			)
			(layer "F.Fab")
		)
		(fp_line
			(start 0.12065 -0.2794)
			(end 0.12065 -0.3048)
			(stroke
				(width 0.1)
				(type default)
			)
			(layer "F.Fab")
		)
		(fp_line
			(start -0.12065 -0.2794)
			(end 0.12065 -0.2794)
			(stroke
				(width 0.1)
				(type default)
			)
			(layer "F.Fab")
		)
		(fp_line
			(start 0.120396 0.2794)
			(end -0.12065 0.2794)
			(stroke
				(width 0.1)
				(type default)
			)
			(layer "F.Fab")
		)
		(fp_line
			(start -0.12065 0.2794)
			(end -0.12065 0.3048)
			(stroke
				(width 0.1)
				(type default)
			)
			(layer "F.Fab")
		)
		(fp_line
			(start 0.67945 0.3048)
			(end 0.120396 0.3048)
			(stroke
				(width 0.1)
				(type default)
			)
			(layer "F.Fab")
		)
		(fp_line
			(start 0.120396 0.3048)
			(end 0.120396 0.2794)
			(stroke
				(width 0.1)
				(type default)
			)
			(layer "F.Fab")
		)
		(fp_line
			(start -0.12065 0.3048)
			(end -0.67945 0.3048)
			(stroke
				(width 0.1)
				(type default)
			)
			(layer "F.Fab")
		)
		(fp_line
			(start -0.67945 0.3048)
			(end -0.67945 -0.305054)
			(stroke
				(width 0.1)
				(type default)
			)
			(layer "F.Fab")
		)
		(pad "1" smd circle
			(at -0.40005 0 90)
			(size 0 0)
			(layers "F.Cu" "F.Mask" "F.Paste")
			(net "P3V3_SSD10_SS")
		)
		(pad "2" smd circle
			(at 0.40005 0 90)
			(size 0 0)
			(layers "F.Cu" "F.Mask" "F.Paste")
			(net "GND")
		)
	)
)
